(kicad_pcb
	(version 20260206)
	(generator "pcbnew")
	(generator_version "10.0")
	(general
		(thickness 1.6)
		(legacy_teardrops no)
	)
	(paper "A4")
	(title_block
		(title "04192023_DAF0TMB3IC0_F0TG_MB_C_brd_V02_OCP.brd")
		(comment 1 "Grand Teton / footprints 2174-2175 of 8354")
	)
	(layers
		(0 "F.Cu" signal "TOP")
		(4 "In1.Cu" signal "GND")
		(6 "In2.Cu" signal "IN1")
		(8 "In3.Cu" signal "GND1")
		(10 "In4.Cu" signal "IN2")
		(12 "In5.Cu" signal "GND2")
		(14 "In6.Cu" signal "IN3")
		(16 "In7.Cu" signal "GND3")
		(18 "In8.Cu" signal "VCC")
		(20 "In9.Cu" signal "VCC1")
		(22 "In10.Cu" signal "GND4")
		(24 "In11.Cu" signal "IN4")
		(26 "In12.Cu" signal "GND5")
		(28 "In13.Cu" signal "IN5")
		(30 "In14.Cu" signal "GND6")
		(32 "In15.Cu" signal "IN6")
		(34 "In16.Cu" signal "GND7")
		(2 "B.Cu" signal "BOTTOM")
		(9 "F.Adhes" user "F.Adhesive")
		(11 "B.Adhes" user "B.Adhesive")
		(13 "F.Paste" user "Package Geometry/Pastemask Top")
		(15 "B.Paste" user "Package Geometry/Pastemask Bottom")
		(5 "F.SilkS" user "Ref Des/Silkscreen Top")
		(7 "B.SilkS" user "Ref Des/Silkscreen Bottom")
		(1 "F.Mask" user "Board Geometry/Soldermask Top")
		(3 "B.Mask" user "Board Geometry/Soldermask Bottom")
		(17 "Dwgs.User" user "User.Drawings")
		(19 "Cmts.User" user "User.Comments")
		(21 "Eco1.User" user "User.Eco1")
		(23 "Eco2.User" user "User.Eco2")
		(25 "Edge.Cuts" user "Board Geometry/Outline")
		(27 "Margin" user)
		(31 "F.CrtYd" user "Package Geometry/Place Bound Top")
		(29 "B.CrtYd" user "Package Geometry/Place Bound Bottom")
		(35 "F.Fab" user "Ref Des/Assembly Top")
		(33 "B.Fab" user "Ref Des/Assembly Bottom")
	)
	(footprint ""
		(layer "F.Cu")
		(at 430.827434 -98.175064 180)
		(property "Reference" "R3645"
			(at 2.202434 2.636266 0)
			(unlocked yes)
			(layer "F.SilkS")
			(effects
				(font
					(size 0.7874 0.5842)
					(thickness 0.1524)
				)
				(justify left)
			)
		)
		(property "Value" ""
			(at 0 0 180)
			(layer "F.Fab")
			(effects
				(font
					(size 1.27 1.27)
				)
			)
		)
		(duplicate_pad_numbers_are_jumpers no)
		(fp_line
			(start 3.937508 1.8796)
			(end 3.937508 -1.8796)
			(stroke
				(width 0.1524)
				(type default)
			)
			(layer "F.SilkS")
		)
		(fp_line
			(start 3.937508 -1.8796)
			(end -3.937508 -1.8796)
			(stroke
				(width 0.1524)
				(type default)
			)
			(layer "F.SilkS")
		)
		(fp_line
			(start -3.937508 1.8796)
			(end 3.937508 1.8796)
			(stroke
				(width 0.1524)
				(type default)
			)
			(layer "F.SilkS")
		)
		(fp_line
			(start -3.937508 -1.8796)
			(end -3.937508 1.8796)
			(stroke
				(width 0.1524)
				(type default)
			)
			(layer "F.SilkS")
		)
		(fp_line
			(start 3.275076 1.674876)
			(end 3.275076 -1.674876)
			(stroke
				(width 0.1)
				(type default)
			)
			(layer "F.Fab")
		)
		(fp_line
			(start 3.275076 -1.674876)
			(end -3.275076 -1.674876)
			(stroke
				(width 0.1)
				(type default)
			)
			(layer "F.Fab")
		)
		(fp_line
			(start -3.275076 1.674876)
			(end 3.275076 1.674876)
			(stroke
				(width 0.1)
				(type default)
			)
			(layer "F.Fab")
		)
		(fp_line
			(start -3.275076 -1.674876)
			(end -3.275076 1.674876)
			(stroke
				(width 0.1)
				(type default)
			)
			(layer "F.Fab")
		)
		(pad "1" smd rect
			(at -2.350008 0 180)
			(size 2.921 3.5052)
			(layers "F.Cu" "F.Mask" "F.Paste")
			(net "P3V3_OCP_SFF")
		)
		(pad "2" smd rect
			(at 2.350008 0 180)
			(size 2.921 3.5052)
			(layers "F.Cu" "F.Mask" "F.Paste")
			(net "P3V3_OCP_SFF_R")
		)
	)
	(footprint ""
		(layer "F.Cu")
		(at 412.743904 -159.116014 90)
		(property "Reference" "PC612"
			(at 0 0 90)
			(layer "F.SilkS")
			(hide yes)
			(effects
				(font
					(size 1.27 1.27)
				)
			)
		)
		(property "Value" ""
			(at 0 0 90)
			(layer "F.Fab")
			(effects
				(font
					(size 1.27 1.27)
				)
			)
		)
		(duplicate_pad_numbers_are_jumpers no)
		(fp_line
			(start 0.7874 -0.4064)
			(end 0.7874 0.4064)
			(stroke
				(width 0.1524)
				(type default)
			)
			(layer "F.SilkS")
		)
		(fp_line
			(start -0.7874 -0.4064)
			(end 0.7874 -0.4064)
			(stroke
				(width 0.1524)
				(type default)
			)
			(layer "F.SilkS")
		)
		(fp_line
			(start 0.7874 0.4064)
			(end -0.7874 0.4064)
			(stroke
				(width 0.1524)
				(type default)
			)
			(layer "F.SilkS")
		)
		(fp_line
			(start -0.7874 0.4064)
			(end -0.7874 -0.4064)
			(stroke
				(width 0.1524)
				(type default)
			)
			(layer "F.SilkS")
		)
		(fp_line
			(start -0.12065 -0.305054)
			(end -0.12065 -0.2794)
			(stroke
				(width 0.1)
				(type default)
			)
			(layer "F.Fab")
		)
		(fp_line
			(start -0.67945 -0.305054)
			(end -0.12065 -0.305054)
			(stroke
				(width 0.1)
				(type default)
			)
			(layer "F.Fab")
		)
		(fp_line
			(start 0.67945 -0.3048)
			(end 0.67945 0.3048)
			(stroke
				(width 0.1)
				(type default)
			)
			(layer "F.Fab")
		)
		(fp_line
			(start 0.12065 -0.3048)
			(end 0.67945 -0.3048)
			(stroke
				(width 0.1)
				(type default)
			)
			(layer "F.Fab")
		)
		(fp_line
			(start 0.12065 -0.2794)
			(end 0.12065 -0.3048)
			(stroke
				(width 0.1)
				(type default)
			)
			(layer "F.Fab")
		)
		(fp_line
			(start -0.12065 -0.2794)
			(end 0.12065 -0.2794)
			(stroke
				(width 0.1)
				(type default)
			)
			(layer "F.Fab")
		)
		(fp_line
			(start 0.120396 0.2794)
			(end -0.12065 0.2794)
			(stroke
				(width 0.1)
				(type default)
			)
			(layer "F.Fab")
		)
		(fp_line
			(start -0.12065 0.2794)
			(end -0.12065 0.3048)
			(stroke
				(width 0.1)
				(type default)
			)
			(layer "F.Fab")
		)
		(fp_line
			(start 0.67945 0.3048)
			(end 0.120396 0.3048)
			(stroke
				(width 0.1)
				(type default)
			)
			(layer "F.Fab")
		)
		(fp_line
			(start 0.120396 0.3048)
			(end 0.120396 0.2794)
			(stroke
				(width 0.1)
				(type default)
			)
			(layer "F.Fab")
		)
		(fp_line
			(start -0.12065 0.3048)
			(end -0.67945 0.3048)
			(stroke
				(width 0.1)
				(type default)
			)
			(layer "F.Fab")
		)
		(fp_line
			(start -0.67945 0.3048)
			(end -0.67945 -0.305054)
			(stroke
				(width 0.1)
				(type default)
			)
			(layer "F.Fab")
		)
		(pad "1" smd circle
			(at -0.40005 0 90)
			(size 0 0)
			(layers "F.Cu" "F.Mask" "F.Paste")
			(net "SW_PVDDCR_SOC_P0_BOOT3_RC")
		)
		(pad "2" smd circle
			(at 0.40005 0 90)
			(size 0 0)
			(layers "F.Cu" "F.Mask" "F.Paste")
			(net "SW_PVDDCR_SOC_P0_PH3")
		)
	)
)
